(kicad_pcb
	(version 20260206)
	(generator "pcbnew")
	(generator_version "10.0")
	(general
		(thickness 1.6)
		(legacy_teardrops no)
	)
	(paper "A4")
	(title_block
		(title "12092022_DA0F0TYB4D0_F0T_Panel_BD_Front_D_brd_v02_OCP.brd")
		(comment 1 "Grand Teton / footprints 21-27 of 128")
	)
	(layers
		(0 "F.Cu" signal "TOP")
		(4 "In1.Cu" signal "GND")
		(6 "In2.Cu" signal "GND1")
		(2 "B.Cu" signal "BOTTOM")
		(9 "F.Adhes" user "F.Adhesive")
		(11 "B.Adhes" user "B.Adhesive")
		(13 "F.Paste" user "Package Geometry/Pastemask Top")
		(15 "B.Paste" user "Package Geometry/Pastemask Bottom")
		(5 "F.SilkS" user "Ref Des/Silkscreen Top")
		(7 "B.SilkS" user "Ref Des/Silkscreen Bottom")
		(1 "F.Mask" user "Board Geometry/Soldermask Top")
		(3 "B.Mask" user "Board Geometry/Soldermask Bottom")
		(17 "Dwgs.User" user "User.Drawings")
		(19 "Cmts.User" user "User.Comments")
		(21 "Eco1.User" user "User.Eco1")
		(23 "Eco2.User" user "User.Eco2")
		(25 "Edge.Cuts" user "Board Geometry/Outline")
		(27 "Margin" user)
		(31 "F.CrtYd" user "Package Geometry/Place Bound Top")
		(29 "B.CrtYd" user "Package Geometry/Place Bound Bottom")
		(35 "F.Fab" user "Ref Des/Assembly Top")
		(33 "B.Fab" user "Ref Des/Assembly Bottom")
	)
	(footprint ""
		(layer "F.Cu")
		(at 18.554954 -14.723618 180)
		(property "Reference" "U2"
			(at -1.384046 2.267712 0)
			(unlocked yes)
			(layer "F.SilkS")
			(effects
				(font
					(size 0.7874 0.5842)
					(thickness 0.1524)
				)
			)
		)
		(property "Value" ""
			(at 0 0 180)
			(layer "F.Fab")
			(effects
				(font
					(size 1.27 1.27)
				)
			)
		)
		(duplicate_pad_numbers_are_jumpers no)
		(fp_line
			(start 1.949958 1.610106)
			(end -1.949958 1.610106)
			(stroke
				(width 0.1524)
				(type default)
			)
			(layer "F.SilkS")
		)
		(fp_line
			(start 1.949958 -1.560068)
			(end 1.949958 1.610106)
			(stroke
				(width 0.1524)
				(type default)
			)
			(layer "F.SilkS")
		)
		(fp_line
			(start -1.949958 1.610106)
			(end -1.949958 -1.610106)
			(stroke
				(width 0.1524)
				(type default)
			)
			(layer "F.SilkS")
		)
		(fp_line
			(start -1.949958 -1.610106)
			(end 1.949958 -1.610106)
			(stroke
				(width 0.1524)
				(type default)
			)
			(layer "F.SilkS")
		)
		(fp_line
			(start 0.750062 1.560068)
			(end -0.750062 1.560068)
			(stroke
				(width 0.1)
				(type default)
			)
			(layer "F.Fab")
		)
		(fp_line
			(start 0.750062 -1.560068)
			(end 0.750062 1.560068)
			(stroke
				(width 0.1)
				(type default)
			)
			(layer "F.Fab")
		)
		(fp_line
			(start -0.750062 1.560068)
			(end -0.750062 -1.560068)
			(stroke
				(width 0.1)
				(type default)
			)
			(layer "F.Fab")
		)
		(fp_line
			(start -0.750062 -1.560068)
			(end 0.750062 -1.560068)
			(stroke
				(width 0.1)
				(type default)
			)
			(layer "F.Fab")
		)
		(pad "D" smd rect
			(at 1.100074 0 90)
			(size 1.016 1.4224)
			(layers "F.Cu" "F.Mask" "F.Paste")
			(net "FM_PFR_LED_BLUE_R")
		)
		(pad "G" smd rect
			(at -1.100074 -0.94996 90)
			(size 1.016 1.4224)
			(layers "F.Cu" "F.Mask" "F.Paste")
			(net "FM_PFR_LED_BLUE_R_N")
		)
		(pad "S" smd rect
			(at -1.100074 0.94996 90)
			(size 1.016 1.4224)
			(layers "F.Cu" "F.Mask" "F.Paste")
			(net "GND")
		)
	)
	(footprint ""
		(layer "F.Cu")
		(at 31.073852 -6.911594 180)
		(property "Reference" "C7"
			(at 0.720852 1.062736 0)
			(unlocked yes)
			(layer "F.SilkS")
			(effects
				(font
					(size 0.7874 0.5842)
					(thickness 0.1524)
				)
			)
		)
		(property "Value" ""
			(at 0 0 180)
			(layer "F.Fab")
			(effects
				(font
					(size 1.27 1.27)
				)
			)
		)
		(duplicate_pad_numbers_are_jumpers no)
		(fp_line
			(start 0.7874 0.4064)
			(end -0.7874 0.4064)
			(stroke
				(width 0.1524)
				(type default)
			)
			(layer "F.SilkS")
		)
		(fp_line
			(start 0.7874 -0.4064)
			(end 0.7874 0.4064)
			(stroke
				(width 0.1524)
				(type default)
			)
			(layer "F.SilkS")
		)
		(fp_line
			(start -0.7874 0.4064)
			(end -0.7874 -0.4064)
			(stroke
				(width 0.1524)
				(type default)
			)
			(layer "F.SilkS")
		)
		(fp_line
			(start -0.7874 -0.4064)
			(end 0.7874 -0.4064)
			(stroke
				(width 0.1524)
				(type default)
			)
			(layer "F.SilkS")
		)
		(fp_line
			(start 0.67945 0.3048)
			(end 0.120396 0.3048)
			(stroke
				(width 0.1)
				(type default)
			)
			(layer "F.Fab")
		)
		(fp_line
			(start 0.67945 -0.3048)
			(end 0.67945 0.3048)
			(stroke
				(width 0.1)
				(type default)
			)
			(layer "F.Fab")
		)
		(fp_line
			(start 0.12065 -0.2794)
			(end 0.12065 -0.3048)
			(stroke
				(width 0.1)
				(type default)
			)
			(layer "F.Fab")
		)
		(fp_line
			(start 0.12065 -0.3048)
			(end 0.67945 -0.3048)
			(stroke
				(width 0.1)
				(type default)
			)
			(layer "F.Fab")
		)
		(fp_line
			(start 0.120396 0.3048)
			(end 0.120396 0.2794)
			(stroke
				(width 0.1)
				(type default)
			)
			(layer "F.Fab")
		)
		(fp_line
			(start 0.120396 0.2794)
			(end -0.12065 0.2794)
			(stroke
				(width 0.1)
				(type default)
			)
			(layer "F.Fab")
		)
		(fp_line
			(start -0.12065 0.3048)
			(end -0.67945 0.3048)
			(stroke
				(width 0.1)
				(type default)
			)
			(layer "F.Fab")
		)
		(fp_line
			(start -0.12065 0.2794)
			(end -0.12065 0.3048)
			(stroke
				(width 0.1)
				(type default)
			)
			(layer "F.Fab")
		)
		(fp_line
			(start -0.12065 -0.2794)
			(end 0.12065 -0.2794)
			(stroke
				(width 0.1)
				(type default)
			)
			(layer "F.Fab")
		)
		(fp_line
			(start -0.12065 -0.305054)
			(end -0.12065 -0.2794)
			(stroke
				(width 0.1)
				(type default)
			)
			(layer "F.Fab")
		)
		(fp_line
			(start -0.67945 0.3048)
			(end -0.67945 -0.305054)
			(stroke
				(width 0.1)
				(type default)
			)
			(layer "F.Fab")
		)
		(fp_line
			(start -0.67945 -0.305054)
			(end -0.12065 -0.305054)
			(stroke
				(width 0.1)
				(type default)
			)
			(layer "F.Fab")
		)
		(pad "1" smd circle
			(at -0.40005 0 180)
			(size 0 0)
			(layers "F.Cu" "F.Mask" "F.Paste")
			(net "P3V3_STBY")
		)
		(pad "2" smd circle
			(at 0.40005 0 180)
			(size 0 0)
			(layers "F.Cu" "F.Mask" "F.Paste")
			(net "GND")
		)
	)
	(footprint ""
		(layer "F.Cu")
		(at 18.288 -67.437)
		(property "Reference" "C2"
			(at 1.778 -0.10033 0)
			(unlocked yes)
			(layer "F.SilkS")
			(effects
				(font
					(size 0.7874 0.5842)
					(thickness 0.1524)
				)
			)
		)
		(property "Value" ""
			(at 0 0 0)
			(layer "F.Fab")
			(effects
				(font
					(size 1.27 1.27)
				)
			)
		)
		(duplicate_pad_numbers_are_jumpers no)
		(fp_line
			(start -0.7874 -0.4064)
			(end 0.7874 -0.4064)
			(stroke
				(width 0.1524)
				(type default)
			)
			(layer "F.SilkS")
		)
		(fp_line
			(start -0.7874 0.4064)
			(end -0.7874 -0.4064)
			(stroke
				(width 0.1524)
				(type default)
			)
			(layer "F.SilkS")
		)
		(fp_line
			(start 0.7874 -0.4064)
			(end 0.7874 0.4064)
			(stroke
				(width 0.1524)
				(type default)
			)
			(layer "F.SilkS")
		)
		(fp_line
			(start 0.7874 0.4064)
			(end -0.7874 0.4064)
			(stroke
				(width 0.1524)
				(type default)
			)
			(layer "F.SilkS")
		)
		(fp_line
			(start -0.67945 -0.305054)
			(end -0.12065 -0.305054)
			(stroke
				(width 0.1)
				(type default)
			)
			(layer "F.Fab")
		)
		(fp_line
			(start -0.67945 0.3048)
			(end -0.67945 -0.305054)
			(stroke
				(width 0.1)
				(type default)
			)
			(layer "F.Fab")
		)
		(fp_line
			(start -0.12065 -0.305054)
			(end -0.12065 -0.2794)
			(stroke
				(width 0.1)
				(type default)
			)
			(layer "F.Fab")
		)
		(fp_line
			(start -0.12065 -0.2794)
			(end 0.12065 -0.2794)
			(stroke
				(width 0.1)
				(type default)
			)
			(layer "F.Fab")
		)
		(fp_line
			(start -0.12065 0.2794)
			(end -0.12065 0.3048)
			(stroke
				(width 0.1)
				(type default)
			)
			(layer "F.Fab")
		)
		(fp_line
			(start -0.12065 0.3048)
			(end -0.67945 0.3048)
			(stroke
				(width 0.1)
				(type default)
			)
			(layer "F.Fab")
		)
		(fp_line
			(start 0.120396 0.2794)
			(end -0.12065 0.2794)
			(stroke
				(width 0.1)
				(type default)
			)
			(layer "F.Fab")
		)
		(fp_line
			(start 0.120396 0.3048)
			(end 0.120396 0.2794)
			(stroke
				(width 0.1)
				(type default)
			)
			(layer "F.Fab")
		)
		(fp_line
			(start 0.12065 -0.3048)
			(end 0.67945 -0.3048)
			(stroke
				(width 0.1)
				(type default)
			)
			(layer "F.Fab")
		)
		(fp_line
			(start 0.12065 -0.2794)
			(end 0.12065 -0.3048)
			(stroke
				(width 0.1)
				(type default)
			)
			(layer "F.Fab")
		)
		(fp_line
			(start 0.67945 -0.3048)
			(end 0.67945 0.3048)
			(stroke
				(width 0.1)
				(type default)
			)
			(layer "F.Fab")
		)
		(fp_line
			(start 0.67945 0.3048)
			(end 0.120396 0.3048)
			(stroke
				(width 0.1)
				(type default)
			)
			(layer "F.Fab")
		)
		(pad "1" smd circle
			(at -0.40005 0)
			(size 0 0)
			(layers "F.Cu" "F.Mask" "F.Paste")
			(net "P3V3_STBY")
		)
		(pad "2" smd circle
			(at 0.40005 0)
			(size 0 0)
			(layers "F.Cu" "F.Mask" "F.Paste")
			(net "GND")
		)
	)
	(footprint ""
		(layer "F.Cu")
		(at 3.937 -47.752)
		(property "Reference" "R56"
			(at -2.413 0.15367 0)
			(unlocked yes)
			(layer "F.SilkS")
			(effects
				(font
					(size 0.7874 0.5842)
					(thickness 0.1524)
				)
			)
		)
		(property "Value" ""
			(at 0 0 0)
			(layer "F.Fab")
			(effects
				(font
					(size 1.27 1.27)
				)
			)
		)
		(duplicate_pad_numbers_are_jumpers no)
		(fp_line
			(start -0.7874 -0.4064)
			(end 0.7874 -0.4064)
			(stroke
				(width 0.1524)
				(type default)
			)
			(layer "F.SilkS")
		)
		(fp_line
			(start -0.7874 0.4064)
			(end -0.7874 -0.4064)
			(stroke
				(width 0.1524)
				(type default)
			)
			(layer "F.SilkS")
		)
		(fp_line
			(start 0.7874 -0.4064)
			(end 0.7874 0.4064)
			(stroke
				(width 0.1524)
				(type default)
			)
			(layer "F.SilkS")
		)
		(fp_line
			(start 0.7874 0.4064)
			(end -0.7874 0.4064)
			(stroke
				(width 0.1524)
				(type default)
			)
			(layer "F.SilkS")
		)
		(fp_line
			(start -0.67945 -0.305054)
			(end -0.12065 -0.305054)
			(stroke
				(width 0.1)
				(type default)
			)
			(layer "F.Fab")
		)
		(fp_line
			(start -0.67945 0.3048)
			(end -0.67945 -0.305054)
			(stroke
				(width 0.1)
				(type default)
			)
			(layer "F.Fab")
		)
		(fp_line
			(start -0.12065 -0.305054)
			(end -0.12065 -0.2794)
			(stroke
				(width 0.1)
				(type default)
			)
			(layer "F.Fab")
		)
		(fp_line
			(start -0.12065 -0.2794)
			(end 0.12065 -0.2794)
			(stroke
				(width 0.1)
				(type default)
			)
			(layer "F.Fab")
		)
		(fp_line
			(start -0.12065 0.2794)
			(end -0.12065 0.3048)
			(stroke
				(width 0.1)
				(type default)
			)
			(layer "F.Fab")
		)
		(fp_line
			(start -0.12065 0.3048)
			(end -0.67945 0.3048)
			(stroke
				(width 0.1)
				(type default)
			)
			(layer "F.Fab")
		)
		(fp_line
			(start 0.120396 0.2794)
			(end -0.12065 0.2794)
			(stroke
				(width 0.1)
				(type default)
			)
			(layer "F.Fab")
		)
		(fp_line
			(start 0.120396 0.3048)
			(end 0.120396 0.2794)
			(stroke
				(width 0.1)
				(type default)
			)
			(layer "F.Fab")
		)
		(fp_line
			(start 0.12065 -0.3048)
			(end 0.67945 -0.3048)
			(stroke
				(width 0.1)
				(type default)
			)
			(layer "F.Fab")
		)
		(fp_line
			(start 0.12065 -0.2794)
			(end 0.12065 -0.3048)
			(stroke
				(width 0.1)
				(type default)
			)
			(layer "F.Fab")
		)
		(fp_line
			(start 0.67945 -0.3048)
			(end 0.67945 0.3048)
			(stroke
				(width 0.1)
				(type default)
			)
			(layer "F.Fab")
		)
		(fp_line
			(start 0.67945 0.3048)
			(end 0.120396 0.3048)
			(stroke
				(width 0.1)
				(type default)
			)
			(layer "F.Fab")
		)
		(pad "1" smd circle
			(at -0.40005 0)
			(size 0 0)
			(layers "F.Cu" "F.Mask" "F.Paste")
			(net "P3V3_STBY")
		)
		(pad "2" smd circle
			(at 0.40005 0)
			(size 0 0)
			(layers "F.Cu" "F.Mask" "F.Paste")
			(net "PD_FRU_A2")
		)
	)
	(footprint ""
		(layer "F.Cu")
		(at 18.415 -60.833 180)
		(property "Reference" "R17"
			(at -3.81 -0.02667 0)
			(unlocked yes)
			(layer "F.SilkS")
			(effects
				(font
					(size 0.7874 0.5842)
					(thickness 0.1524)
				)
			)
		)
		(property "Value" ""
			(at 0 0 180)
			(layer "F.Fab")
			(effects
				(font
					(size 1.27 1.27)
				)
			)
		)
		(duplicate_pad_numbers_are_jumpers no)
		(fp_line
			(start 0.7874 0.4064)
			(end -0.7874 0.4064)
			(stroke
				(width 0.1524)
				(type default)
			)
			(layer "F.SilkS")
		)
		(fp_line
			(start 0.7874 -0.4064)
			(end 0.7874 0.4064)
			(stroke
				(width 0.1524)
				(type default)
			)
			(layer "F.SilkS")
		)
		(fp_line
			(start -0.7874 0.4064)
			(end -0.7874 -0.4064)
			(stroke
				(width 0.1524)
				(type default)
			)
			(layer "F.SilkS")
		)
		(fp_line
			(start -0.7874 -0.4064)
			(end 0.7874 -0.4064)
			(stroke
				(width 0.1524)
				(type default)
			)
			(layer "F.SilkS")
		)
		(fp_line
			(start 0.67945 0.3048)
			(end 0.120396 0.3048)
			(stroke
				(width 0.1)
				(type default)
			)
			(layer "F.Fab")
		)
		(fp_line
			(start 0.67945 -0.3048)
			(end 0.67945 0.3048)
			(stroke
				(width 0.1)
				(type default)
			)
			(layer "F.Fab")
		)
		(fp_line
			(start 0.12065 -0.2794)
			(end 0.12065 -0.3048)
			(stroke
				(width 0.1)
				(type default)
			)
			(layer "F.Fab")
		)
		(fp_line
			(start 0.12065 -0.3048)
			(end 0.67945 -0.3048)
			(stroke
				(width 0.1)
				(type default)
			)
			(layer "F.Fab")
		)
		(fp_line
			(start 0.120396 0.3048)
			(end 0.120396 0.2794)
			(stroke
				(width 0.1)
				(type default)
			)
			(layer "F.Fab")
		)
		(fp_line
			(start 0.120396 0.2794)
			(end -0.12065 0.2794)
			(stroke
				(width 0.1)
				(type default)
			)
			(layer "F.Fab")
		)
		(fp_line
			(start -0.12065 0.3048)
			(end -0.67945 0.3048)
			(stroke
				(width 0.1)
				(type default)
			)
			(layer "F.Fab")
		)
		(fp_line
			(start -0.12065 0.2794)
			(end -0.12065 0.3048)
			(stroke
				(width 0.1)
				(type default)
			)
			(layer "F.Fab")
		)
		(fp_line
			(start -0.12065 -0.2794)
			(end 0.12065 -0.2794)
			(stroke
				(width 0.1)
				(type default)
			)
			(layer "F.Fab")
		)
		(fp_line
			(start -0.12065 -0.305054)
			(end -0.12065 -0.2794)
			(stroke
				(width 0.1)
				(type default)
			)
			(layer "F.Fab")
		)
		(fp_line
			(start -0.67945 0.3048)
			(end -0.67945 -0.305054)
			(stroke
				(width 0.1)
				(type default)
			)
			(layer "F.Fab")
		)
		(fp_line
			(start -0.67945 -0.305054)
			(end -0.12065 -0.305054)
			(stroke
				(width 0.1)
				(type default)
			)
			(layer "F.Fab")
		)
		(pad "1" smd circle
			(at -0.40005 0 180)
			(size 0 0)
			(layers "F.Cu" "F.Mask" "F.Paste")
			(net "SMB_SDA")
		)
		(pad "2" smd circle
			(at 0.40005 0 180)
			(size 0 0)
			(layers "F.Cu" "F.Mask" "F.Paste")
			(net "SMB_EXP_SDA")
		)
	)
	(footprint ""
		(layer "F.Cu")
		(at 23.495 -30.48)
		(property "Reference" "R66"
			(at 0.381 -0.98933 0)
			(unlocked yes)
			(layer "F.SilkS")
			(effects
				(font
					(size 0.7874 0.5842)
					(thickness 0.1524)
				)
			)
		)
		(property "Value" ""
			(at 0 0 0)
			(layer "F.Fab")
			(effects
				(font
					(size 1.27 1.27)
				)
			)
		)
		(duplicate_pad_numbers_are_jumpers no)
		(fp_line
			(start -0.7874 -0.4064)
			(end 0.7874 -0.4064)
			(stroke
				(width 0.1524)
				(type default)
			)
			(layer "F.SilkS")
		)
		(fp_line
			(start -0.7874 0.4064)
			(end -0.7874 -0.4064)
			(stroke
				(width 0.1524)
				(type default)
			)
			(layer "F.SilkS")
		)
		(fp_line
			(start 0.7874 -0.4064)
			(end 0.7874 0.4064)
			(stroke
				(width 0.1524)
				(type default)
			)
			(layer "F.SilkS")
		)
		(fp_line
			(start 0.7874 0.4064)
			(end -0.7874 0.4064)
			(stroke
				(width 0.1524)
				(type default)
			)
			(layer "F.SilkS")
		)
		(fp_line
			(start -0.67945 -0.305054)
			(end -0.12065 -0.305054)
			(stroke
				(width 0.1)
				(type default)
			)
			(layer "F.Fab")
		)
		(fp_line
			(start -0.67945 0.3048)
			(end -0.67945 -0.305054)
			(stroke
				(width 0.1)
				(type default)
			)
			(layer "F.Fab")
		)
		(fp_line
			(start -0.12065 -0.305054)
			(end -0.12065 -0.2794)
			(stroke
				(width 0.1)
				(type default)
			)
			(layer "F.Fab")
		)
		(fp_line
			(start -0.12065 -0.2794)
			(end 0.12065 -0.2794)
			(stroke
				(width 0.1)
				(type default)
			)
			(layer "F.Fab")
		)
		(fp_line
			(start -0.12065 0.2794)
			(end -0.12065 0.3048)
			(stroke
				(width 0.1)
				(type default)
			)
			(layer "F.Fab")
		)
		(fp_line
			(start -0.12065 0.3048)
			(end -0.67945 0.3048)
			(stroke
				(width 0.1)
				(type default)
			)
			(layer "F.Fab")
		)
		(fp_line
			(start 0.120396 0.2794)
			(end -0.12065 0.2794)
			(stroke
				(width 0.1)
				(type default)
			)
			(layer "F.Fab")
		)
		(fp_line
			(start 0.120396 0.3048)
			(end 0.120396 0.2794)
			(stroke
				(width 0.1)
				(type default)
			)
			(layer "F.Fab")
		)
		(fp_line
			(start 0.12065 -0.3048)
			(end 0.67945 -0.3048)
			(stroke
				(width 0.1)
				(type default)
			)
			(layer "F.Fab")
		)
		(fp_line
			(start 0.12065 -0.2794)
			(end 0.12065 -0.3048)
			(stroke
				(width 0.1)
				(type default)
			)
			(layer "F.Fab")
		)
		(fp_line
			(start 0.67945 -0.3048)
			(end 0.67945 0.3048)
			(stroke
				(width 0.1)
				(type default)
			)
			(layer "F.Fab")
		)
		(fp_line
			(start 0.67945 0.3048)
			(end 0.120396 0.3048)
			(stroke
				(width 0.1)
				(type default)
			)
			(layer "F.Fab")
		)
		(pad "1" smd circle
			(at -0.40005 0)
			(size 0 0)
			(layers "F.Cu" "F.Mask" "F.Paste")
			(net "UART_DEBUG_R_RX")
		)
		(pad "2" smd circle
			(at 0.40005 0)
			(size 0 0)
			(layers "F.Cu" "F.Mask" "F.Paste")
			(net "UART_DEBUG_RX")
		)
	)
	(footprint ""
		(layer "F.Cu")
		(at 32.385 -34.163 180)
		(property "Reference" "C14"
			(at 1.016 7.33933 0)
			(unlocked yes)
			(layer "F.SilkS")
			(effects
				(font
					(size 0.7874 0.5842)
					(thickness 0.1524)
				)
				(justify left)
			)
		)
		(property "Value" ""
			(at 0 0 180)
			(layer "F.Fab")
			(effects
				(font
					(size 1.27 1.27)
				)
			)
		)
		(duplicate_pad_numbers_are_jumpers no)
		(fp_line
			(start 1.524 0.762)
			(end -1.524 0.762)
			(stroke
				(width 0.1524)
				(type default)
			)
			(layer "F.SilkS")
		)
		(fp_line
			(start 1.524 -0.762)
			(end 1.524 0.762)
			(stroke
				(width 0.1524)
				(type default)
			)
			(layer "F.SilkS")
		)
		(fp_line
			(start -1.524 0.762)
			(end -1.524 -0.762)
			(stroke
				(width 0.1524)
				(type default)
			)
			(layer "F.SilkS")
		)
		(fp_line
			(start -1.524 -0.762)
			(end 1.524 -0.762)
			(stroke
				(width 0.1524)
				(type default)
			)
			(layer "F.SilkS")
		)
		(fp_line
			(start 1.1049 0.724916)
			(end 1.1049 -0.724916)
			(stroke
				(width 0.1)
				(type default)
			)
			(layer "F.Fab")
		)
		(fp_line
			(start 1.1049 -0.724916)
			(end -1.1049 -0.724916)
			(stroke
				(width 0.1)
				(type default)
			)
			(layer "F.Fab")
		)
		(fp_line
			(start -1.1049 0.724916)
			(end 1.1049 0.724916)
			(stroke
				(width 0.1)
				(type default)
			)
			(layer "F.Fab")
		)
		(fp_line
			(start -1.1049 -0.724916)
			(end -1.1049 0.724916)
			(stroke
				(width 0.1)
				(type default)
			)
			(layer "F.Fab")
		)
		(pad "1" smd rect
			(at -0.889 0)
			(size 1.016 1.27)
			(layers "F.Cu" "F.Mask" "F.Paste")
			(net "P5V_STBY_DEBUG")
		)
		(pad "2" smd rect
			(at 0.889 0)
			(size 1.016 1.27)
			(layers "F.Cu" "F.Mask" "F.Paste")
			(net "GND")
		)
	)
)
